# T6G (Grand Teton) — schematic netlist excerpt (pin names and nets, part order shuffled) for the footprints in the layout excerpt that follows; sources: Cadence DE-HDL packaged netlist, KiCad conversion of 04192023_DAF0TMB3IC0_F0TG_MB_C_brd_V02_OCP.brd

R1220  Q_RES  18K 1% CHIP  pkg 0402LF  page 258 : A = P1V8_CPU0_RT_1D_ADC ; B = GND
PC6569  Q_CAPP  470UF 2.5V 20% SPCAP  pkg SMLF  page 363 : A = P0V9_CPU0_RT_2D ; B = GND

(kicad_pcb
	(version 20260206)
	(generator "pcbnew")
	(generator_version "10.0")
	(general
		(thickness 1.6)
		(legacy_teardrops no)
	)
	(paper "A4")
	(title_block
		(title "04192023_DAF0TMB3IC0_F0TG_MB_C_brd_V02_OCP.brd")
		(comment 1 "Grand Teton / footprints 8324-8325 of 8354")
	)
	(layers
		(0 "F.Cu" signal "TOP")
		(4 "In1.Cu" signal "GND")
		(6 "In2.Cu" signal "IN1")
		(8 "In3.Cu" signal "GND1")
		(10 "In4.Cu" signal "IN2")
		(12 "In5.Cu" signal "GND2")
		(14 "In6.Cu" signal "IN3")
		(16 "In7.Cu" signal "GND3")
		(18 "In8.Cu" signal "VCC")
		(20 "In9.Cu" signal "VCC1")
		(22 "In10.Cu" signal "GND4")
		(24 "In11.Cu" signal "IN4")
		(26 "In12.Cu" signal "GND5")
		(28 "In13.Cu" signal "IN5")
		(30 "In14.Cu" signal "GND6")
		(32 "In15.Cu" signal "IN6")
		(34 "In16.Cu" signal "GND7")
		(2 "B.Cu" signal "BOTTOM")
		(9 "F.Adhes" user "F.Adhesive")
		(11 "B.Adhes" user "B.Adhesive")
		(13 "F.Paste" user "Package Geometry/Pastemask Top")
		(15 "B.Paste" user "Package Geometry/Pastemask Bottom")
		(5 "F.SilkS" user "Ref Des/Silkscreen Top")
		(7 "B.SilkS" user "Ref Des/Silkscreen Bottom")
		(1 "F.Mask" user "Board Geometry/Soldermask Top")
		(3 "B.Mask" user "Board Geometry/Soldermask Bottom")
		(17 "Dwgs.User" user "User.Drawings")
		(19 "Cmts.User" user "User.Comments")
		(21 "Eco1.User" user "User.Eco1")
		(23 "Eco2.User" user "User.Eco2")
		(25 "Edge.Cuts" user "Board Geometry/Outline")
		(27 "Margin" user)
		(31 "F.CrtYd" user "Package Geometry/Place Bound Top")
		(29 "B.CrtYd" user "Package Geometry/Place Bound Bottom")
		(35 "F.Fab" user "Ref Des/Assembly Top")
		(33 "B.Fab" user "Ref Des/Assembly Bottom")
	)
	(footprint ""
		(layer "B.Cu")
		(at 456.028552 -380.027434 90)
		(property "Reference" "PC6569"
			(at -6.293104 2.441448 0)
			(unlocked yes)
			(layer "B.SilkS")
			(effects
				(font
					(size 0.7874 0.5842)
					(thickness 0.1524)
				)
				(justify left mirror)
			)
		)
		(property "Value" ""
			(at 0 0 90)
			(layer "B.Fab")
			(effects
				(font
					(size 1.27 1.27)
				)
				(justify mirror)
			)
		)
		(duplicate_pad_numbers_are_jumpers no)
		(fp_line
			(start 4.84378 -2.150618)
			(end 4.53898 -2.150618)
			(stroke
				(width 0.1524)
				(type default)
			)
			(layer "B.SilkS")
		)
		(fp_line
			(start 4.84378 -2.150618)
			(end 4.842256 2.163064)
			(stroke
				(width 0.1524)
				(type default)
			)
			(layer "B.SilkS")
		)
		(fp_line
			(start 4.69138 -2.150618)
			(end 4.692396 2.161032)
			(stroke
				(width 0.1524)
				(type default)
			)
			(layer "B.SilkS")
		)
		(fp_line
			(start 4.53898 -2.150618)
			(end 4.539742 2.152142)
			(stroke
				(width 0.1524)
				(type default)
			)
			(layer "B.SilkS")
		)
		(fp_line
			(start 4.53898 -2.15011)
			(end -4.53898 -2.15011)
			(stroke
				(width 0.1524)
				(type default)
			)
			(layer "B.SilkS")
		)
		(fp_line
			(start -4.53898 -2.15011)
			(end -4.53898 2.15011)
			(stroke
				(width 0.1524)
				(type default)
			)
			(layer "B.SilkS")
		)
		(fp_line
			(start 4.53898 2.15011)
			(end 4.53898 -2.15011)
			(stroke
				(width 0.1524)
				(type default)
			)
			(layer "B.SilkS")
		)
		(fp_line
			(start -4.53898 2.15011)
			(end 4.53898 2.15011)
			(stroke
				(width 0.1524)
				(type default)
			)
			(layer "B.SilkS")
		)
		(fp_line
			(start 4.83108 2.150364)
			(end 4.447794 2.149348)
			(stroke
				(width 0.1524)
				(type default)
			)
			(layer "B.SilkS")
		)
		(fp_line
			(start 3.64998 -2.15011)
			(end -3.64998 -2.15011)
			(stroke
				(width 0.1)
				(type default)
			)
			(layer "B.Fab")
		)
		(fp_line
			(start -3.64998 -2.15011)
			(end -3.64998 2.15011)
			(stroke
				(width 0.1)
				(type default)
			)
			(layer "B.Fab")
		)
		(fp_line
			(start 3.64998 2.15011)
			(end 3.64998 -2.15011)
			(stroke
				(width 0.1)
				(type default)
			)
			(layer "B.Fab")
		)
		(fp_line
			(start -3.64998 2.15011)
			(end 3.64998 2.15011)
			(stroke
				(width 0.1)
				(type default)
			)
			(layer "B.Fab")
		)
		(fp_text user "+"
			(at 5.235702 -3.104388 90)
			(unlocked yes)
			(layer "B.SilkS")
			(effects
				(font
					(size 1.905 1.4224)
					(thickness 0.1524)
				)
				(justify left mirror)
			)
		)
		(fp_text user "-"
			(at -4.313174 -0.094488 90)
			(unlocked yes)
			(layer "B.SilkS")
			(effects
				(font
					(size 1.905 1.4224)
					(thickness 0.1524)
				)
				(justify left mirror)
			)
		)
		(fp_text user "+"
			(at 6.214872 -0.337058 90)
			(unlocked yes)
			(layer "B.Fab")
			(effects
				(font
					(size 1.905 1.4224)
					(thickness 0.1524)
				)
				(justify left mirror)
			)
		)
		(fp_text user "-"
			(at -4.313174 -0.094488 90)
			(unlocked yes)
			(layer "B.Fab")
			(effects
				(font
					(size 1.905 1.4224)
					(thickness 0.1524)
				)
				(justify left mirror)
			)
		)
		(pad "1" smd rect
			(at 3.199892 0 270)
			(size 2.413 2.8194)
			(layers "B.Cu" "B.Mask" "B.Paste")
			(net "P0V9_CPU0_RT_2D")
		)
		(pad "2" smd rect
			(at -3.199892 0 270)
			(size 2.413 2.8194)
			(layers "B.Cu" "B.Mask" "B.Paste")
			(net "GND")
		)
	)
	(footprint ""
		(layer "B.Cu")
		(at 234.843828 -324.793102 180)
		(property "Reference" "R1220"
			(at 0 0 0)
			(layer "B.SilkS")
			(hide yes)
			(effects
				(font
					(size 1.27 1.27)
				)
				(justify mirror)
			)
		)
		(property "Value" ""
			(at 0 0 0)
			(layer "B.Fab")
			(effects
				(font
					(size 1.27 1.27)
				)
				(justify mirror)
			)
		)
		(duplicate_pad_numbers_are_jumpers no)
		(fp_line
			(start 0.7874 0.4064)
			(end 0.7874 -0.4064)
			(stroke
				(width 0.1524)
				(type default)
			)
			(layer "B.SilkS")
		)
		(fp_line
			(start 0.7874 -0.4064)
			(end -0.7874 -0.4064)
			(stroke
				(width 0.1524)
				(type default)
			)
			(layer "B.SilkS")
		)
		(fp_line
			(start -0.7874 0.4064)
			(end 0.7874 0.4064)
			(stroke
				(width 0.1524)
				(type default)
			)
			(layer "B.SilkS")
		)
		(fp_line
			(start -0.7874 -0.4064)
			(end -0.7874 0.4064)
			(stroke
				(width 0.1524)
				(type default)
			)
			(layer "B.SilkS")
		)
		(fp_line
			(start 0.67945 0.3048)
			(end 0.67945 -0.305054)
			(stroke
				(width 0.1)
				(type default)
			)
			(layer "B.Fab")
		)
		(fp_line
			(start 0.67945 -0.305054)
			(end 0.12065 -0.305054)
			(stroke
				(width 0.1)
				(type default)
			)
			(layer "B.Fab")
		)
		(fp_line
			(start 0.12065 0.3048)
			(end 0.67945 0.3048)
			(stroke
				(width 0.1)
				(type default)
			)
			(layer "B.Fab")
		)
		(fp_line
			(start 0.12065 0.2794)
			(end 0.12065 0.3048)
			(stroke
				(width 0.1)
				(type default)
			)
			(layer "B.Fab")
		)
		(fp_line
			(start 0.12065 -0.2794)
			(end -0.12065 -0.2794)
			(stroke
				(width 0.1)
				(type default)
			)
			(layer "B.Fab")
		)
		(fp_line
			(start 0.12065 -0.305054)
			(end 0.12065 -0.2794)
			(stroke
				(width 0.1)
				(type default)
			)
			(layer "B.Fab")
		)
		(fp_line
			(start -0.120396 0.3048)
			(end -0.120396 0.2794)
			(stroke
				(width 0.1)
				(type default)
			)
			(layer "B.Fab")
		)
		(fp_line
			(start -0.120396 0.2794)
			(end 0.12065 0.2794)
			(stroke
				(width 0.1)
				(type default)
			)
			(layer "B.Fab")
		)
		(fp_line
			(start -0.12065 -0.2794)
			(end -0.12065 -0.3048)
			(stroke
				(width 0.1)
				(type default)
			)
			(layer "B.Fab")
		)
		(fp_line
			(start -0.12065 -0.3048)
			(end -0.67945 -0.3048)
			(stroke
				(width 0.1)
				(type default)
			)
			(layer "B.Fab")
		)
		(fp_line
			(start -0.67945 0.3048)
			(end -0.120396 0.3048)
			(stroke
				(width 0.1)
				(type default)
			)
			(layer "B.Fab")
		)
		(fp_line
			(start -0.67945 -0.3048)
			(end -0.67945 0.3048)
			(stroke
				(width 0.1)
				(type default)
			)
			(layer "B.Fab")
		)
		(pad "1" smd circle
			(at 0.40005 0)
			(size 0 0)
			(layers "B.Cu" "B.Mask" "B.Paste")
			(net "P1V8_CPU0_RT_1D_ADC")
		)
		(pad "2" smd circle
			(at -0.40005 0)
			(size 0 0)
			(layers "B.Cu" "B.Mask" "B.Paste")
			(net "GND")
		)
	)
)
